(kicad_pcb
	(version 20260206)
	(generator "pcbnew")
	(generator_version "10.0")
	(general
		(thickness 1.6)
		(legacy_teardrops no)
	)
	(paper "A4")
	(title_block
		(title "03242023_DA0F0TMBIJ0_F0T_Motherboard_J_brd_V01_OCP.brd")
		(comment 1 "Grand Teton / footprints 247-250 of 6105")
	)
	(layers
		(0 "F.Cu" signal "TOP")
		(4 "In1.Cu" signal "GND")
		(6 "In2.Cu" signal "IN1")
		(8 "In3.Cu" signal "GND1")
		(10 "In4.Cu" signal "IN2")
		(12 "In5.Cu" signal "GND2")
		(14 "In6.Cu" signal "IN3")
		(16 "In7.Cu" signal "GND3")
		(18 "In8.Cu" signal "VCC")
		(20 "In9.Cu" signal "VCC1")
		(22 "In10.Cu" signal "GND4")
		(24 "In11.Cu" signal "IN4")
		(26 "In12.Cu" signal "GND5")
		(28 "In13.Cu" signal "IN5")
		(30 "In14.Cu" signal "GND6")
		(32 "In15.Cu" signal "IN6")
		(34 "In16.Cu" signal "GND7")
		(2 "B.Cu" signal "BOTTOM")
		(9 "F.Adhes" user "F.Adhesive")
		(11 "B.Adhes" user "B.Adhesive")
		(13 "F.Paste" user "Package Geometry/Pastemask Top")
		(15 "B.Paste" user "Package Geometry/Pastemask Bottom")
		(5 "F.SilkS" user "Ref Des/Silkscreen Top")
		(7 "B.SilkS" user "Ref Des/Silkscreen Bottom")
		(1 "F.Mask" user "Board Geometry/Soldermask Top")
		(3 "B.Mask" user "Board Geometry/Soldermask Bottom")
		(17 "Dwgs.User" user "User.Drawings")
		(19 "Cmts.User" user "User.Comments")
		(21 "Eco1.User" user "User.Eco1")
		(23 "Eco2.User" user "User.Eco2")
		(25 "Edge.Cuts" user "Board Geometry/Outline")
		(27 "Margin" user)
		(31 "F.CrtYd" user "Package Geometry/Place Bound Top")
		(29 "B.CrtYd" user "Package Geometry/Place Bound Bottom")
		(35 "F.Fab" user "Ref Des/Assembly Top")
		(33 "B.Fab" user "Ref Des/Assembly Bottom")
	)
	(footprint ""
		(layer "F.Cu")
		(at 298.368974 -412.80588)
		(property "Reference" "U331"
			(at -0.517652 -2.589022 0)
			(unlocked yes)
			(layer "F.SilkS")
			(effects
				(font
					(size 0.7874 0.5842)
					(thickness 0.1524)
				)
			)
		)
		(property "Value" ""
			(at 0 0 0)
			(layer "F.Fab")
			(effects
				(font
					(size 1.27 1.27)
				)
			)
		)
		(duplicate_pad_numbers_are_jumpers no)
		(fp_line
			(start -1.500124 -1.500124)
			(end -1.004062 -1.500124)
			(stroke
				(width 0.1524)
				(type default)
			)
			(layer "F.SilkS")
		)
		(fp_line
			(start -1.500124 -1.004062)
			(end -1.500124 -1.500124)
			(stroke
				(width 0.1524)
				(type default)
			)
			(layer "F.SilkS")
		)
		(fp_line
			(start -1.500124 1.500124)
			(end -1.500124 1.004062)
			(stroke
				(width 0.1524)
				(type default)
			)
			(layer "F.SilkS")
		)
		(fp_line
			(start -1.004062 1.500124)
			(end -1.500124 1.500124)
			(stroke
				(width 0.1524)
				(type default)
			)
			(layer "F.SilkS")
		)
		(fp_line
			(start 1.004062 -1.500124)
			(end 1.500124 -1.500124)
			(stroke
				(width 0.1524)
				(type default)
			)
			(layer "F.SilkS")
		)
		(fp_line
			(start 1.500124 -1.500124)
			(end 1.500124 -1.004062)
			(stroke
				(width 0.1524)
				(type default)
			)
			(layer "F.SilkS")
		)
		(fp_line
			(start 1.500124 1.004062)
			(end 1.500124 1.500124)
			(stroke
				(width 0.1524)
				(type default)
			)
			(layer "F.SilkS")
		)
		(fp_line
			(start 1.500124 1.500124)
			(end 1.004062 1.500124)
			(stroke
				(width 0.1524)
				(type default)
			)
			(layer "F.SilkS")
		)
		(fp_poly
			(pts
				(xy -2.1844 -1.649984) (xy -2.902966 -0.931418) (xy -1.825244 -0.572262)
			)
			(stroke
				(width 0)
				(type default)
			)
			(fill yes)
			(layer "F.SilkS")
		)
		(fp_line
			(start -1.500124 -1.500124)
			(end 1.500124 -1.500124)
			(stroke
				(width 0.1)
				(type default)
			)
			(layer "F.Fab")
		)
		(fp_line
			(start -1.500124 1.500124)
			(end -1.500124 -1.500124)
			(stroke
				(width 0.1)
				(type default)
			)
			(layer "F.Fab")
		)
		(fp_line
			(start 1.500124 -1.500124)
			(end 1.500124 1.500124)
			(stroke
				(width 0.1)
				(type default)
			)
			(layer "F.Fab")
		)
		(fp_line
			(start 1.500124 1.500124)
			(end -1.500124 1.500124)
			(stroke
				(width 0.1)
				(type default)
			)
			(layer "F.Fab")
		)
		(fp_poly
			(pts
				(xy -2.847848 -1.258062) (xy -2.847848 -0.242062) (xy -1.831848 -0.750062)
			)
			(stroke
				(width 0)
				(type default)
			)
			(fill yes)
			(layer "F.Fab")
		)
		(pad "1" smd rect
			(at -1.400048 -0.750062 270)
			(size 0.2286 0.6096)
			(layers "F.Cu" "F.Mask" "F.Paste")
			(net "HSC_TYPE_ADC_A1")
		)
		(pad "2" smd rect
			(at -1.400048 -0.249936 270)
			(size 0.2286 0.6096)
			(layers "F.Cu" "F.Mask" "F.Paste")
			(net "HSC_TYPE_ADC_A0")
		)
		(pad "3" smd rect
			(at -1.400048 0.249936 270)
			(size 0.2286 0.6096)
			(layers "F.Cu" "F.Mask" "F.Paste")
			(net "TP_HSC_TYPE_ADC_ALERT")
		)
		(pad "4" smd rect
			(at -1.400048 0.750062 270)
			(size 0.2286 0.6096)
			(layers "F.Cu" "F.Mask" "F.Paste")
			(net "SMB_HSC_TYPE_ADC_SDA")
		)
		(pad "5" smd rect
			(at -0.750062 1.400048)
			(size 0.2286 0.6096)
			(layers "F.Cu" "F.Mask" "F.Paste")
			(net "SMB_HSC_TYPE_ADC_SCL")
		)
		(pad "6" smd rect
			(at -0.249936 1.400048)
			(size 0.2286 0.6096)
			(layers "F.Cu" "F.Mask" "F.Paste")
			(net "NC_HSC_TYPE_NC0")
		)
		(pad "7" smd rect
			(at 0.249936 1.400048)
			(size 0.2286 0.6096)
			(layers "F.Cu" "F.Mask" "F.Paste")
			(net "NC_HSC_TYPE_NC1")
		)
		(pad "8" smd rect
			(at 0.750062 1.400048)
			(size 0.2286 0.6096)
			(layers "F.Cu" "F.Mask" "F.Paste")
			(net "NC_HSC_TYPE_NC2")
		)
		(pad "9" smd rect
			(at 1.400048 0.750062 270)
			(size 0.2286 0.6096)
			(layers "F.Cu" "F.Mask" "F.Paste")
			(net "P3V3_AUX")
		)
		(pad "10" smd rect
			(at 1.400048 0.249936 270)
			(size 0.2286 0.6096)
			(layers "F.Cu" "F.Mask" "F.Paste")
			(net "GND")
		)
		(pad "11" smd rect
			(at 1.400048 -0.249936 270)
			(size 0.2286 0.6096)
			(layers "F.Cu" "F.Mask" "F.Paste")
			(net "HSC_TYPE_ADC")
		)
		(pad "12" smd rect
			(at 1.400048 -0.750062 270)
			(size 0.2286 0.6096)
			(layers "F.Cu" "F.Mask" "F.Paste")
			(net "NC_HSC_TYPE_VINM")
		)
		(pad "13" smd rect
			(at 0.750062 -1.400048)
			(size 0.2286 0.6096)
			(layers "F.Cu" "F.Mask" "F.Paste")
			(net "NC_HSC_TYPE_VINP")
		)
		(pad "14" smd rect
			(at 0.249936 -1.400048)
			(size 0.2286 0.6096)
			(layers "F.Cu" "F.Mask" "F.Paste")
			(net "NC_HSC_TYPE_NC3")
		)
		(pad "15" smd rect
			(at -0.249936 -1.400048)
			(size 0.2286 0.6096)
			(layers "F.Cu" "F.Mask" "F.Paste")
			(net "NC_HSC_TYPE_NC4")
		)
		(pad "16" smd rect
			(at -0.750062 -1.400048)
			(size 0.2286 0.6096)
			(layers "F.Cu" "F.Mask" "F.Paste")
			(net "NC_HSC_TYPE_NC5")
		)
		(pad "TH" smd rect
			(at 0 0)
			(size 1.7018 1.7018)
			(layers "F.Cu" "F.Mask" "F.Paste")
			(net "GND")
		)
	)
	(footprint ""
		(layer "F.Cu")
		(at 85.262466 -336.935572 -90)
		(property "Reference" "PC503_P1_6"
			(at 0 0 270)
			(layer "F.SilkS")
			(hide yes)
			(effects
				(font
					(size 1.27 1.27)
				)
			)
		)
		(property "Value" ""
			(at 0 0 270)
			(layer "F.Fab")
			(effects
				(font
					(size 1.27 1.27)
				)
			)
		)
		(duplicate_pad_numbers_are_jumpers no)
		(fp_line
			(start -0.7874 0.4064)
			(end -0.7874 -0.4064)
			(stroke
				(width 0.1524)
				(type default)
			)
			(layer "F.SilkS")
		)
		(fp_line
			(start 0.7874 0.4064)
			(end -0.7874 0.4064)
			(stroke
				(width 0.1524)
				(type default)
			)
			(layer "F.SilkS")
		)
		(fp_line
			(start -0.7874 -0.4064)
			(end 0.7874 -0.4064)
			(stroke
				(width 0.1524)
				(type default)
			)
			(layer "F.SilkS")
		)
		(fp_line
			(start 0.7874 -0.4064)
			(end 0.7874 0.4064)
			(stroke
				(width 0.1524)
				(type default)
			)
			(layer "F.SilkS")
		)
		(fp_line
			(start -0.67945 0.3048)
			(end -0.67945 -0.305054)
			(stroke
				(width 0.1)
				(type default)
			)
			(layer "F.Fab")
		)
		(fp_line
			(start -0.12065 0.3048)
			(end -0.67945 0.3048)
			(stroke
				(width 0.1)
				(type default)
			)
			(layer "F.Fab")
		)
		(fp_line
			(start 0.120396 0.3048)
			(end 0.120396 0.2794)
			(stroke
				(width 0.1)
				(type default)
			)
			(layer "F.Fab")
		)
		(fp_line
			(start 0.67945 0.3048)
			(end 0.120396 0.3048)
			(stroke
				(width 0.1)
				(type default)
			)
			(layer "F.Fab")
		)
		(fp_line
			(start -0.12065 0.2794)
			(end -0.12065 0.3048)
			(stroke
				(width 0.1)
				(type default)
			)
			(layer "F.Fab")
		)
		(fp_line
			(start 0.120396 0.2794)
			(end -0.12065 0.2794)
			(stroke
				(width 0.1)
				(type default)
			)
			(layer "F.Fab")
		)
		(fp_line
			(start -0.12065 -0.2794)
			(end 0.12065 -0.2794)
			(stroke
				(width 0.1)
				(type default)
			)
			(layer "F.Fab")
		)
		(fp_line
			(start 0.12065 -0.2794)
			(end 0.12065 -0.3048)
			(stroke
				(width 0.1)
				(type default)
			)
			(layer "F.Fab")
		)
		(fp_line
			(start 0.12065 -0.3048)
			(end 0.67945 -0.3048)
			(stroke
				(width 0.1)
				(type default)
			)
			(layer "F.Fab")
		)
		(fp_line
			(start 0.67945 -0.3048)
			(end 0.67945 0.3048)
			(stroke
				(width 0.1)
				(type default)
			)
			(layer "F.Fab")
		)
		(fp_line
			(start -0.67945 -0.305054)
			(end -0.12065 -0.305054)
			(stroke
				(width 0.1)
				(type default)
			)
			(layer "F.Fab")
		)
		(fp_line
			(start -0.12065 -0.305054)
			(end -0.12065 -0.2794)
			(stroke
				(width 0.1)
				(type default)
			)
			(layer "F.Fab")
		)
		(pad "1" smd circle
			(at -0.40005 0 270)
			(size 0 0)
			(layers "F.Cu" "F.Mask" "F.Paste")
			(net "PVCCIN_CPU1_PVCC")
		)
		(pad "2" smd circle
			(at 0.40005 0 270)
			(size 0 0)
			(layers "F.Cu" "F.Mask" "F.Paste")
			(net "GND")
		)
	)
	(footprint ""
		(layer "F.Cu")
		(at 293.399718 -362.843826 -90)
		(property "Reference" "PC1174_P0_4"
			(at 0 0 270)
			(layer "F.SilkS")
			(hide yes)
			(effects
				(font
					(size 1.27 1.27)
				)
			)
		)
		(property "Value" ""
			(at 0 0 270)
			(layer "F.Fab")
			(effects
				(font
					(size 1.27 1.27)
				)
			)
		)
		(duplicate_pad_numbers_are_jumpers no)
		(fp_line
			(start -0.7874 0.4064)
			(end -0.7874 -0.4064)
			(stroke
				(width 0.1524)
				(type default)
			)
			(layer "F.SilkS")
		)
		(fp_line
			(start 0.7874 0.4064)
			(end -0.7874 0.4064)
			(stroke
				(width 0.1524)
				(type default)
			)
			(layer "F.SilkS")
		)
		(fp_line
			(start -0.7874 -0.4064)
			(end 0.7874 -0.4064)
			(stroke
				(width 0.1524)
				(type default)
			)
			(layer "F.SilkS")
		)
		(fp_line
			(start 0.7874 -0.4064)
			(end 0.7874 0.4064)
			(stroke
				(width 0.1524)
				(type default)
			)
			(layer "F.SilkS")
		)
		(fp_line
			(start -0.67945 0.3048)
			(end -0.67945 -0.305054)
			(stroke
				(width 0.1)
				(type default)
			)
			(layer "F.Fab")
		)
		(fp_line
			(start -0.12065 0.3048)
			(end -0.67945 0.3048)
			(stroke
				(width 0.1)
				(type default)
			)
			(layer "F.Fab")
		)
		(fp_line
			(start 0.120396 0.3048)
			(end 0.120396 0.2794)
			(stroke
				(width 0.1)
				(type default)
			)
			(layer "F.Fab")
		)
		(fp_line
			(start 0.67945 0.3048)
			(end 0.120396 0.3048)
			(stroke
				(width 0.1)
				(type default)
			)
			(layer "F.Fab")
		)
		(fp_line
			(start -0.12065 0.2794)
			(end -0.12065 0.3048)
			(stroke
				(width 0.1)
				(type default)
			)
			(layer "F.Fab")
		)
		(fp_line
			(start 0.120396 0.2794)
			(end -0.12065 0.2794)
			(stroke
				(width 0.1)
				(type default)
			)
			(layer "F.Fab")
		)
		(fp_line
			(start -0.12065 -0.2794)
			(end 0.12065 -0.2794)
			(stroke
				(width 0.1)
				(type default)
			)
			(layer "F.Fab")
		)
		(fp_line
			(start 0.12065 -0.2794)
			(end 0.12065 -0.3048)
			(stroke
				(width 0.1)
				(type default)
			)
			(layer "F.Fab")
		)
		(fp_line
			(start 0.12065 -0.3048)
			(end 0.67945 -0.3048)
			(stroke
				(width 0.1)
				(type default)
			)
			(layer "F.Fab")
		)
		(fp_line
			(start 0.67945 -0.3048)
			(end 0.67945 0.3048)
			(stroke
				(width 0.1)
				(type default)
			)
			(layer "F.Fab")
		)
		(fp_line
			(start -0.67945 -0.305054)
			(end -0.12065 -0.305054)
			(stroke
				(width 0.1)
				(type default)
			)
			(layer "F.Fab")
		)
		(fp_line
			(start -0.12065 -0.305054)
			(end -0.12065 -0.2794)
			(stroke
				(width 0.1)
				(type default)
			)
			(layer "F.Fab")
		)
		(pad "1" smd circle
			(at -0.40005 0 270)
			(size 0 0)
			(layers "F.Cu" "F.Mask" "F.Paste")
			(net "SW_P12V_PVCCFA_EHV_FIVRA_CPU0_L")
		)
		(pad "2" smd circle
			(at 0.40005 0 270)
			(size 0 0)
			(layers "F.Cu" "F.Mask" "F.Paste")
			(net "GND")
		)
	)
	(footprint ""
		(layer "F.Cu")
		(at 260.731508 0.383794)
		(property "Reference" "J77"
			(at -4.164838 0.886206 90)
			(unlocked yes)
			(layer "F.SilkS")
			(effects
				(font
					(size 0.7874 0.5842)
					(thickness 0.1524)
				)
				(justify left)
			)
		)
		(property "Value" ""
			(at 0 0 0)
			(layer "F.Fab")
			(effects
				(font
					(size 1.27 1.27)
				)
			)
		)
		(duplicate_pad_numbers_are_jumpers no)
		(fp_line
			(start -1.2192 -2.1082)
			(end 1.2192 -2.1082)
			(stroke
				(width 0.1524)
				(type default)
			)
			(layer "F.SilkS")
		)
		(fp_line
			(start -1.2192 2.1082)
			(end -1.2192 -2.1082)
			(stroke
				(width 0.1524)
				(type default)
			)
			(layer "F.SilkS")
		)
		(fp_line
			(start 1.2192 -2.1082)
			(end 1.2192 2.1082)
			(stroke
				(width 0.1524)
				(type default)
			)
			(layer "F.SilkS")
		)
		(fp_line
			(start 1.2192 2.1082)
			(end -1.2192 2.1082)
			(stroke
				(width 0.1524)
				(type default)
			)
			(layer "F.SilkS")
		)
		(pad "" np_thru_hole circle
			(at -2.8829 -1.27 270)
			(size 1.0414 1.0414)
			(drill 1.0414)
			(layers "*.Cu" "*.Mask")
			(clearance 0.381)
			(thermal_gap 0.381)
		)
		(pad "" np_thru_hole circle
			(at -2.8829 1.27 270)
			(size 1.0414 1.0414)
			(drill 1.0414)
			(layers "*.Cu" "*.Mask")
			(clearance 0.381)
			(thermal_gap 0.381)
		)
		(pad "" np_thru_hole circle
			(at 3.4671 -1.27 270)
			(size 1.0414 1.0414)
			(drill 1.0414)
			(layers "*.Cu" "*.Mask")
			(clearance 0.381)
			(thermal_gap 0.381)
		)
		(pad "" np_thru_hole circle
			(at 3.4671 1.27 270)
			(size 1.0414 1.0414)
			(drill 1.0414)
			(layers "*.Cu" "*.Mask")
			(clearance 0.381)
			(thermal_gap 0.381)
		)
		(pad "1" smd rect
			(at 0.8255 -0.249936 270)
			(size 0.3048 0.508)
			(layers "F.Cu" "F.Mask" "F.Paste")
			(net "DELTA_L_85_10INCH_IN1_DP")
		)
		(pad "2" smd rect
			(at 0.8255 0.249936 270)
			(size 0.3048 0.508)
			(layers "F.Cu" "F.Mask" "F.Paste")
			(net "DELTA_L_85_10INCH_IN1_DN")
		)
		(pad "3" smd circle
			(at 0 0)
			(size 0 0)
			(layers "F.Cu" "F.Mask" "F.Paste")
			(net "DELTA_L_GND_1")
		)
		(zone
			(layer "F.Cu")
			(hatch none 0.5)
			(connect_pads
				(clearance 0)
			)
			(min_thickness 0.25)
			(keepout
				(tracks not_allowed)
				(vias allowed)
				(pads allowed)
				(copperpour not_allowed)
				(footprints allowed)
			)
			(placement
				(enabled no)
				(sheetname "")
			)
			(fill
				(thermal_gap 0.5)
				(thermal_bridge_width 0.5)
				(island_removal_mode 0)
			)
			(polygon
				(pts
					(xy 261.849108 -0.164846) (xy 261.849108 -0.069342) (xy 261.252208 -0.069342) (xy 261.252208 0.337058)
					(xy 261.849108 0.337058) (xy 261.849108 0.43053) (xy 261.252208 0.43053) (xy 261.252208 0.83693)
					(xy 261.849108 0.83693) (xy 261.849108 0.932434) (xy 261.150608 0.932434) (xy 261.150608 -0.164846)
				)
			)
		)
		(zone
			(layers "F.Cu" "B.Cu" "In1.Cu" "In2.Cu" "In3.Cu" "In4.Cu" "In5.Cu" "In6.Cu"
				"In7.Cu" "In8.Cu" "In9.Cu" "In10.Cu" "In11.Cu" "In12.Cu" "In13.Cu" "In14.Cu"
				"In15.Cu" "In16.Cu"
			)
			(hatch none 0.5)
			(connect_pads
				(clearance 0)
			)
			(min_thickness 0.25)
			(keepout
				(tracks not_allowed)
				(vias allowed)
				(pads allowed)
				(copperpour not_allowed)
				(footprints allowed)
			)
			(placement
				(enabled no)
				(sheetname "")
			)
			(fill
				(thermal_gap 0.5)
				(thermal_bridge_width 0.5)
				(island_removal_mode 0)
			)
			(polygon
				(pts
					(arc
						(start 258.775708 -0.886206)
						(mid 256.921508 -0.886206)
						(end 258.775708 -0.886206)
					)
				)
			)
		)
		(zone
			(layers "F.Cu" "B.Cu" "In1.Cu" "In2.Cu" "In3.Cu" "In4.Cu" "In5.Cu" "In6.Cu"
				"In7.Cu" "In8.Cu" "In9.Cu" "In10.Cu" "In11.Cu" "In12.Cu" "In13.Cu" "In14.Cu"
				"In15.Cu" "In16.Cu"
			)
			(hatch none 0.5)
			(connect_pads
				(clearance 0)
			)
			(min_thickness 0.25)
			(keepout
				(tracks not_allowed)
				(vias allowed)
				(pads allowed)
				(copperpour not_allowed)
				(footprints allowed)
			)
			(placement
				(enabled no)
				(sheetname "")
			)
			(fill
				(thermal_gap 0.5)
				(thermal_bridge_width 0.5)
				(island_removal_mode 0)
			)
			(polygon
				(pts
					(arc
						(start 258.775708 1.653794)
						(mid 256.921508 1.653794)
						(end 258.775708 1.653794)
					)
				)
			)
		)
		(zone
			(layers "F.Cu" "B.Cu" "In1.Cu" "In2.Cu" "In3.Cu" "In4.Cu" "In5.Cu" "In6.Cu"
				"In7.Cu" "In8.Cu" "In9.Cu" "In10.Cu" "In11.Cu" "In12.Cu" "In13.Cu" "In14.Cu"
				"In15.Cu" "In16.Cu"
			)
			(hatch none 0.5)
			(connect_pads
				(clearance 0)
			)
			(min_thickness 0.25)
			(keepout
				(tracks not_allowed)
				(vias allowed)
				(pads allowed)
				(copperpour not_allowed)
				(footprints allowed)
			)
			(placement
				(enabled no)
				(sheetname "")
			)
			(fill
				(thermal_gap 0.5)
				(thermal_bridge_width 0.5)
				(island_removal_mode 0)
			)
			(polygon
				(pts
					(arc
						(start 265.125708 -0.886206)
						(mid 263.271508 -0.886206)
						(end 265.125708 -0.886206)
					)
				)
			)
		)
		(zone
			(layers "F.Cu" "B.Cu" "In1.Cu" "In2.Cu" "In3.Cu" "In4.Cu" "In5.Cu" "In6.Cu"
				"In7.Cu" "In8.Cu" "In9.Cu" "In10.Cu" "In11.Cu" "In12.Cu" "In13.Cu" "In14.Cu"
				"In15.Cu" "In16.Cu"
			)
			(hatch none 0.5)
			(connect_pads
				(clearance 0)
			)
			(min_thickness 0.25)
			(keepout
				(tracks not_allowed)
				(vias allowed)
				(pads allowed)
				(copperpour not_allowed)
				(footprints allowed)
			)
			(placement
				(enabled no)
				(sheetname "")
			)
			(fill
				(thermal_gap 0.5)
				(thermal_bridge_width 0.5)
				(island_removal_mode 0)
			)
			(polygon
				(pts
					(arc
						(start 265.125708 1.653794)
						(mid 263.271508 1.653794)
						(end 265.125708 1.653794)
					)
				)
			)
		)
	)
)
